# S9S_MB_2U (Grand Teton) — schematic netlist excerpt (pin names and nets, part order shuffled) for the footprints in the layout excerpt that follows; sources: Cadence DE-HDL packaged netlist, KiCad conversion of 03242023_DA0F0TMBIJ0_F0T_Motherboard_J_brd_V01_OCP.brd

U365  MMBT3904  EMPTY  pkg SMLF  page 305
  \1\  = P12V_HSC_TEMP_R
  \3\  = P12V_HSC_TEMP_R
  \2\  = P12V_HSC_TEMP_E

PR353  Q_RES  8.87K 1% EMPTY  pkg 0402LF  page 271 : A = PVCCFA_EHV_FIVRA_CPU0_LSET2 ; B = GND

(kicad_pcb
	(version 20260206)
	(generator "pcbnew")
	(generator_version "10.0")
	(general
		(thickness 1.6)
		(legacy_teardrops no)
	)
	(paper "A4")
	(title_block
		(title "03242023_DA0F0TMBIJ0_F0T_Motherboard_J_brd_V01_OCP.brd")
		(comment 1 "Grand Teton / footprints 3142-3143 of 6105")
	)
	(layers
		(0 "F.Cu" signal "TOP")
		(4 "In1.Cu" signal "GND")
		(6 "In2.Cu" signal "IN1")
		(8 "In3.Cu" signal "GND1")
		(10 "In4.Cu" signal "IN2")
		(12 "In5.Cu" signal "GND2")
		(14 "In6.Cu" signal "IN3")
		(16 "In7.Cu" signal "GND3")
		(18 "In8.Cu" signal "VCC")
		(20 "In9.Cu" signal "VCC1")
		(22 "In10.Cu" signal "GND4")
		(24 "In11.Cu" signal "IN4")
		(26 "In12.Cu" signal "GND5")
		(28 "In13.Cu" signal "IN5")
		(30 "In14.Cu" signal "GND6")
		(32 "In15.Cu" signal "IN6")
		(34 "In16.Cu" signal "GND7")
		(2 "B.Cu" signal "BOTTOM")
		(9 "F.Adhes" user "F.Adhesive")
		(11 "B.Adhes" user "B.Adhesive")
		(13 "F.Paste" user "Package Geometry/Pastemask Top")
		(15 "B.Paste" user "Package Geometry/Pastemask Bottom")
		(5 "F.SilkS" user "Ref Des/Silkscreen Top")
		(7 "B.SilkS" user "Ref Des/Silkscreen Bottom")
		(1 "F.Mask" user "Board Geometry/Soldermask Top")
		(3 "B.Mask" user "Board Geometry/Soldermask Bottom")
		(17 "Dwgs.User" user "User.Drawings")
		(19 "Cmts.User" user "User.Comments")
		(21 "Eco1.User" user "User.Eco1")
		(23 "Eco2.User" user "User.Eco2")
		(25 "Edge.Cuts" user "Board Geometry/Outline")
		(27 "Margin" user)
		(31 "F.CrtYd" user "Package Geometry/Place Bound Top")
		(29 "B.CrtYd" user "Package Geometry/Place Bound Bottom")
		(35 "F.Fab" user "Ref Des/Assembly Top")
		(33 "B.Fab" user "Ref Des/Assembly Bottom")
	)
	(footprint ""
		(layer "F.Cu")
		(at 297.183048 -367.919508)
		(property "Reference" "PR353"
			(at 0 0 0)
			(layer "F.SilkS")
			(hide yes)
			(effects
				(font
					(size 1.27 1.27)
				)
			)
		)
		(property "Value" ""
			(at 0 0 0)
			(layer "F.Fab")
			(effects
				(font
					(size 1.27 1.27)
				)
			)
		)
		(duplicate_pad_numbers_are_jumpers no)
		(fp_line
			(start -0.7874 -0.4064)
			(end 0.7874 -0.4064)
			(stroke
				(width 0.1524)
				(type default)
			)
			(layer "F.SilkS")
		)
		(fp_line
			(start -0.7874 0.4064)
			(end -0.7874 -0.4064)
			(stroke
				(width 0.1524)
				(type default)
			)
			(layer "F.SilkS")
		)
		(fp_line
			(start 0.7874 -0.4064)
			(end 0.7874 0.4064)
			(stroke
				(width 0.1524)
				(type default)
			)
			(layer "F.SilkS")
		)
		(fp_line
			(start 0.7874 0.4064)
			(end -0.7874 0.4064)
			(stroke
				(width 0.1524)
				(type default)
			)
			(layer "F.SilkS")
		)
		(fp_line
			(start -0.67945 -0.305054)
			(end -0.12065 -0.305054)
			(stroke
				(width 0.1)
				(type default)
			)
			(layer "F.Fab")
		)
		(fp_line
			(start -0.67945 0.3048)
			(end -0.67945 -0.305054)
			(stroke
				(width 0.1)
				(type default)
			)
			(layer "F.Fab")
		)
		(fp_line
			(start -0.12065 -0.305054)
			(end -0.12065 -0.2794)
			(stroke
				(width 0.1)
				(type default)
			)
			(layer "F.Fab")
		)
		(fp_line
			(start -0.12065 -0.2794)
			(end 0.12065 -0.2794)
			(stroke
				(width 0.1)
				(type default)
			)
			(layer "F.Fab")
		)
		(fp_line
			(start -0.12065 0.2794)
			(end -0.12065 0.3048)
			(stroke
				(width 0.1)
				(type default)
			)
			(layer "F.Fab")
		)
		(fp_line
			(start -0.12065 0.3048)
			(end -0.67945 0.3048)
			(stroke
				(width 0.1)
				(type default)
			)
			(layer "F.Fab")
		)
		(fp_line
			(start 0.120396 0.2794)
			(end -0.12065 0.2794)
			(stroke
				(width 0.1)
				(type default)
			)
			(layer "F.Fab")
		)
		(fp_line
			(start 0.120396 0.3048)
			(end 0.120396 0.2794)
			(stroke
				(width 0.1)
				(type default)
			)
			(layer "F.Fab")
		)
		(fp_line
			(start 0.12065 -0.3048)
			(end 0.67945 -0.3048)
			(stroke
				(width 0.1)
				(type default)
			)
			(layer "F.Fab")
		)
		(fp_line
			(start 0.12065 -0.2794)
			(end 0.12065 -0.3048)
			(stroke
				(width 0.1)
				(type default)
			)
			(layer "F.Fab")
		)
		(fp_line
			(start 0.67945 -0.3048)
			(end 0.67945 0.3048)
			(stroke
				(width 0.1)
				(type default)
			)
			(layer "F.Fab")
		)
		(fp_line
			(start 0.67945 0.3048)
			(end 0.120396 0.3048)
			(stroke
				(width 0.1)
				(type default)
			)
			(layer "F.Fab")
		)
		(pad "1" smd circle
			(at -0.40005 0)
			(size 0 0)
			(layers "F.Cu" "F.Mask" "F.Paste")
			(net "PVCCFA_EHV_FIVRA_CPU0_LSET2")
		)
		(pad "2" smd circle
			(at 0.40005 0)
			(size 0 0)
			(layers "F.Cu" "F.Mask" "F.Paste")
			(net "GND")
		)
	)
	(footprint ""
		(layer "F.Cu")
		(at 283.32176 -399.04162 90)
		(property "Reference" "U365"
			(at -1.905 -2.25933 90)
			(unlocked yes)
			(layer "F.SilkS")
			(effects
				(font
					(size 0.7874 0.5842)
					(thickness 0.1524)
				)
				(justify left)
			)
		)
		(property "Value" ""
			(at 0 0 90)
			(layer "F.Fab")
			(effects
				(font
					(size 1.27 1.27)
				)
			)
		)
		(duplicate_pad_numbers_are_jumpers no)
		(fp_line
			(start 1.905 -1.651)
			(end 1.905 1.651)
			(stroke
				(width 0.1524)
				(type default)
			)
			(layer "F.SilkS")
		)
		(fp_line
			(start -1.905 -1.651)
			(end 1.905 -1.651)
			(stroke
				(width 0.1524)
				(type default)
			)
			(layer "F.SilkS")
		)
		(fp_line
			(start 1.905 1.651)
			(end -1.905 1.651)
			(stroke
				(width 0.1524)
				(type default)
			)
			(layer "F.SilkS")
		)
		(fp_line
			(start -1.905 1.651)
			(end -1.905 -1.651)
			(stroke
				(width 0.1524)
				(type default)
			)
			(layer "F.SilkS")
		)
		(fp_line
			(start 0.6985 -1.524)
			(end 0.6985 -0.219964)
			(stroke
				(width 0.1)
				(type default)
			)
			(layer "F.Fab")
		)
		(fp_line
			(start -0.649986 -1.524)
			(end 0.6985 -1.524)
			(stroke
				(width 0.1)
				(type default)
			)
			(layer "F.Fab")
		)
		(fp_line
			(start -0.649986 -1.169924)
			(end -0.649986 -1.524)
			(stroke
				(width 0.1)
				(type default)
			)
			(layer "F.Fab")
		)
		(fp_line
			(start -1.249934 -1.169924)
			(end -0.649986 -1.169924)
			(stroke
				(width 0.1)
				(type default)
			)
			(layer "F.Fab")
		)
		(fp_line
			(start -0.6985 -0.729996)
			(end -1.249934 -0.729996)
			(stroke
				(width 0.1)
				(type default)
			)
			(layer "F.Fab")
		)
		(fp_line
			(start -1.249934 -0.729996)
			(end -1.249934 -1.169924)
			(stroke
				(width 0.1)
				(type default)
			)
			(layer "F.Fab")
		)
		(fp_line
			(start 1.249934 -0.219964)
			(end 1.249934 0.219964)
			(stroke
				(width 0.1)
				(type default)
			)
			(layer "F.Fab")
		)
		(fp_line
			(start 0.6985 -0.219964)
			(end 1.249934 -0.219964)
			(stroke
				(width 0.1)
				(type default)
			)
			(layer "F.Fab")
		)
		(fp_line
			(start 1.249934 0.219964)
			(end 0.6985 0.219964)
			(stroke
				(width 0.1)
				(type default)
			)
			(layer "F.Fab")
		)
		(fp_line
			(start 0.6985 0.219964)
			(end 0.6985 1.524)
			(stroke
				(width 0.1)
				(type default)
			)
			(layer "F.Fab")
		)
		(fp_line
			(start -0.6985 0.729996)
			(end -0.6985 -0.729996)
			(stroke
				(width 0.1)
				(type default)
			)
			(layer "F.Fab")
		)
		(fp_line
			(start -1.249934 0.729996)
			(end -0.6985 0.729996)
			(stroke
				(width 0.1)
				(type default)
			)
			(layer "F.Fab")
		)
		(fp_line
			(start -0.649986 1.169924)
			(end -1.249934 1.169924)
			(stroke
				(width 0.1)
				(type default)
			)
			(layer "F.Fab")
		)
		(fp_line
			(start -1.249934 1.169924)
			(end -1.249934 0.729996)
			(stroke
				(width 0.1)
				(type default)
			)
			(layer "F.Fab")
		)
		(fp_line
			(start 0.6985 1.524)
			(end -0.649986 1.524)
			(stroke
				(width 0.1)
				(type default)
			)
			(layer "F.Fab")
		)
		(fp_line
			(start -0.649986 1.524)
			(end -0.649986 1.169924)
			(stroke
				(width 0.1)
				(type default)
			)
			(layer "F.Fab")
		)
		(pad "B" smd rect
			(at -1.1176 -1.016)
			(size 1.016 1.27)
			(layers "F.Cu" "F.Mask" "F.Paste")
			(net "P12V_HSC_TEMP_R")
		)
		(pad "C" smd rect
			(at 1.1176 0)
			(size 1.016 1.27)
			(layers "F.Cu" "F.Mask" "F.Paste")
			(net "P12V_HSC_TEMP_R")
		)
		(pad "E" smd rect
			(at -1.1176 1.016)
			(size 1.016 1.27)
			(layers "F.Cu" "F.Mask" "F.Paste")
			(net "P12V_HSC_TEMP_E")
		)
	)
)
